#ISCELL
  mstr_misc dns *
  *
#ISCELL
  pure_quanta quanta_title_block_c *
  *
#CELL
  pure_quanta q_cap *
  page245_i100
#CELL
  pure_quanta q_cap *
  page245_i101
#ISCELL
  logical_power gnd *
  page245_i102
#CELL
  pure_quanta q_capp *
  page245_i103
#CELL
  pure_quanta q_capp *
  page245_i104
#CELL
  pure_quanta q_cap *
  page245_i105
#CELL
  pure_quanta q_cap *
  page245_i106
#CELL
  pure_quanta q_cap *
  page245_i107
#CELL
  pure_quanta q_cap *
  page245_i108
#CELL
  pure_quanta q_cap *
  page245_i109
#CELL
  pure_quanta q_cap *
  page245_i110
#CELL
  pure_quanta q_cap *
  page245_i111
#CELL
  pure_quanta q_cap *
  page245_i112
#CELL
  pure_quanta q_cap *
  page245_i113
#CELL
  pure_quanta q_cap *
  page245_i114
#CELL
  pure_quanta q_cap *
  page245_i115
#ISCELL
  logical_power universal_power *
  page245_i116
#ISCELL
  logical_power gnd *
  page245_i117
#CELL
  pure_quanta q_cap *
  page245_i118
#ISCELL
  logical_power gnd *
  page245_i119
#ISCELL
  logical_power gnd *
  page245_i120
#CELL
  pure_quanta q_res *
  page245_i121
#CELL
  pure_quanta q_cap *
  page245_i122
#CELL
  pure_quanta q_res *
  page245_i123
#ISCELL
  logical_power gnd *
  page245_i124
#CELL
  pure_quanta q_res *
  page245_i125
#ISCELL
  logical_power universal_power *
  page245_i126
#CELL
  pure_quanta q_cap *
  page245_i127
#CELL
  pure_quanta q_res *
  page245_i128
#CELL
  pure_quanta q_inductor *
  page245_i129
#ISCELL
  standard offpage *
  page245_i130
#CELL
  pure_quanta q_capp *
  page245_i131
#CELL
  pure_quanta q_capp *
  page245_i132
#CELL
  pure_quanta q_cap *
  page245_i133
#CELL
  pure_quanta q_cap *
  page245_i134
#ISCELL
  logical_power gnd *
  page245_i135
#CELL
  pure_quanta q_cap *
  page245_i136
#CELL
  pure_quanta q_cap *
  page245_i137
#ISCELL
  logical_power universal_power *
  page245_i138
#CELL
  pure_quanta q_res *
  page245_i139
#ISCELL
  logical_power universal_power *
  page245_i140
#CELL
  pure_quanta q_diode *
  page245_i71
#CELL
  pure_quanta q_res *
  page245_i72
#CELL
  pure_quanta q_cap *
  page245_i73
#ISCELL
  logical_power gnd *
  page245_i74
#ISCELL
  logical_power gnd *
  page245_i75
#CELL
  pure_quanta q_res *
  page245_i76
#ISCELL
  logical_power gnd *
  page245_i77
#CELL
  pure_quanta q_res *
  page245_i78
#ISCELL
  standard offpage *
  page245_i79
#ISCELL
  logical_power p1v0_aux *
  page245_i80
#ISCELL
  logical_power gnd *
  page245_i83
#CELL
  pure_quanta q_res *
  page245_i84
#CELL
  pure_quanta q_cap *
  page245_i86
#ISCELL
  logical_power gnd *
  page245_i87
#ISCELL
  logical_power gnd *
  page245_i88
#CELL
  pure_quanta q_res *
  page245_i89
#ISCELL
  logical_power gnd *
  page245_i90
#CELL
  pure_quanta q_res *
  page245_i91
#ISCELL
  logical_power gnd *
  page245_i92
#CELL
  pure_quanta q_cap *
  page245_i93
#CELL
  pure_quanta q_res *
  page245_i94
#CELL
  pure_quanta ir3889mtrpbf *
  page245_i95
#ISCELL
  logical_power gnd *
  page245_i96
#CELL
  pure_quanta q_cap *
  page245_i97
#CELL
  pure_quanta q_inductor *
  page245_i98
#ISCELL
  logical_power universal_power *
  page245_i99
